(kicad_pcb
	(version 20260206)
	(generator "pcbnew")
	(generator_version "10.0")
	(general
		(thickness 1.6)
		(legacy_teardrops no)
	)
	(paper "A4")
	(title_block
		(title "03242023_DA0F0TMBIJ0_F0T_Motherboard_J_brd_V01_OCP.brd")
		(comment 1 "Grand Teton / footprints 710-715 of 6105")
	)
	(layers
		(0 "F.Cu" signal "TOP")
		(4 "In1.Cu" signal "GND")
		(6 "In2.Cu" signal "IN1")
		(8 "In3.Cu" signal "GND1")
		(10 "In4.Cu" signal "IN2")
		(12 "In5.Cu" signal "GND2")
		(14 "In6.Cu" signal "IN3")
		(16 "In7.Cu" signal "GND3")
		(18 "In8.Cu" signal "VCC")
		(20 "In9.Cu" signal "VCC1")
		(22 "In10.Cu" signal "GND4")
		(24 "In11.Cu" signal "IN4")
		(26 "In12.Cu" signal "GND5")
		(28 "In13.Cu" signal "IN5")
		(30 "In14.Cu" signal "GND6")
		(32 "In15.Cu" signal "IN6")
		(34 "In16.Cu" signal "GND7")
		(2 "B.Cu" signal "BOTTOM")
		(9 "F.Adhes" user "F.Adhesive")
		(11 "B.Adhes" user "B.Adhesive")
		(13 "F.Paste" user "Package Geometry/Pastemask Top")
		(15 "B.Paste" user "Package Geometry/Pastemask Bottom")
		(5 "F.SilkS" user "Ref Des/Silkscreen Top")
		(7 "B.SilkS" user "Ref Des/Silkscreen Bottom")
		(1 "F.Mask" user "Board Geometry/Soldermask Top")
		(3 "B.Mask" user "Board Geometry/Soldermask Bottom")
		(17 "Dwgs.User" user "User.Drawings")
		(19 "Cmts.User" user "User.Comments")
		(21 "Eco1.User" user "User.Eco1")
		(23 "Eco2.User" user "User.Eco2")
		(25 "Edge.Cuts" user "Board Geometry/Outline")
		(27 "Margin" user)
		(31 "F.CrtYd" user "Package Geometry/Place Bound Top")
		(29 "B.CrtYd" user "Package Geometry/Place Bound Bottom")
		(35 "F.Fab" user "Ref Des/Assembly Top")
		(33 "B.Fab" user "Ref Des/Assembly Bottom")
	)
	(footprint ""
		(layer "F.Cu")
		(at 56.618378 -81.345024 90)
		(property "Reference" "R3092"
			(at 0 0 90)
			(layer "F.SilkS")
			(hide yes)
			(effects
				(font
					(size 1.27 1.27)
				)
			)
		)
		(property "Value" ""
			(at 0 0 90)
			(layer "F.Fab")
			(effects
				(font
					(size 1.27 1.27)
				)
			)
		)
		(duplicate_pad_numbers_are_jumpers no)
		(fp_line
			(start 0.7874 -0.4064)
			(end 0.7874 0.4064)
			(stroke
				(width 0.1524)
				(type default)
			)
			(layer "F.SilkS")
		)
		(fp_line
			(start -0.7874 -0.4064)
			(end 0.7874 -0.4064)
			(stroke
				(width 0.1524)
				(type default)
			)
			(layer "F.SilkS")
		)
		(fp_line
			(start 0.7874 0.4064)
			(end -0.7874 0.4064)
			(stroke
				(width 0.1524)
				(type default)
			)
			(layer "F.SilkS")
		)
		(fp_line
			(start -0.7874 0.4064)
			(end -0.7874 -0.4064)
			(stroke
				(width 0.1524)
				(type default)
			)
			(layer "F.SilkS")
		)
		(fp_line
			(start -0.12065 -0.305054)
			(end -0.12065 -0.2794)
			(stroke
				(width 0.1)
				(type default)
			)
			(layer "F.Fab")
		)
		(fp_line
			(start -0.67945 -0.305054)
			(end -0.12065 -0.305054)
			(stroke
				(width 0.1)
				(type default)
			)
			(layer "F.Fab")
		)
		(fp_line
			(start 0.67945 -0.3048)
			(end 0.67945 0.3048)
			(stroke
				(width 0.1)
				(type default)
			)
			(layer "F.Fab")
		)
		(fp_line
			(start 0.12065 -0.3048)
			(end 0.67945 -0.3048)
			(stroke
				(width 0.1)
				(type default)
			)
			(layer "F.Fab")
		)
		(fp_line
			(start 0.12065 -0.2794)
			(end 0.12065 -0.3048)
			(stroke
				(width 0.1)
				(type default)
			)
			(layer "F.Fab")
		)
		(fp_line
			(start -0.12065 -0.2794)
			(end 0.12065 -0.2794)
			(stroke
				(width 0.1)
				(type default)
			)
			(layer "F.Fab")
		)
		(fp_line
			(start 0.120396 0.2794)
			(end -0.12065 0.2794)
			(stroke
				(width 0.1)
				(type default)
			)
			(layer "F.Fab")
		)
		(fp_line
			(start -0.12065 0.2794)
			(end -0.12065 0.3048)
			(stroke
				(width 0.1)
				(type default)
			)
			(layer "F.Fab")
		)
		(fp_line
			(start 0.67945 0.3048)
			(end 0.120396 0.3048)
			(stroke
				(width 0.1)
				(type default)
			)
			(layer "F.Fab")
		)
		(fp_line
			(start 0.120396 0.3048)
			(end 0.120396 0.2794)
			(stroke
				(width 0.1)
				(type default)
			)
			(layer "F.Fab")
		)
		(fp_line
			(start -0.12065 0.3048)
			(end -0.67945 0.3048)
			(stroke
				(width 0.1)
				(type default)
			)
			(layer "F.Fab")
		)
		(fp_line
			(start -0.67945 0.3048)
			(end -0.67945 -0.305054)
			(stroke
				(width 0.1)
				(type default)
			)
			(layer "F.Fab")
		)
		(pad "1" smd circle
			(at -0.40005 0 90)
			(size 0 0)
			(layers "F.Cu" "F.Mask" "F.Paste")
			(net "LED_PWRGD_PVCCINFAON_CPU0")
		)
		(pad "2" smd circle
			(at 0.40005 0 90)
			(size 0 0)
			(layers "F.Cu" "F.Mask" "F.Paste")
			(net "P3V3_AUX")
		)
	)
	(footprint ""
		(layer "F.Cu")
		(at 350.78416 -357.562658)
		(property "Reference" "R2368"
			(at 0 0 0)
			(layer "F.SilkS")
			(hide yes)
			(effects
				(font
					(size 1.27 1.27)
				)
			)
		)
		(property "Value" ""
			(at 0 0 0)
			(layer "F.Fab")
			(effects
				(font
					(size 1.27 1.27)
				)
			)
		)
		(duplicate_pad_numbers_are_jumpers no)
		(fp_line
			(start -0.7874 -0.4064)
			(end 0.7874 -0.4064)
			(stroke
				(width 0.1524)
				(type default)
			)
			(layer "F.SilkS")
		)
		(fp_line
			(start -0.7874 0.4064)
			(end -0.7874 -0.4064)
			(stroke
				(width 0.1524)
				(type default)
			)
			(layer "F.SilkS")
		)
		(fp_line
			(start 0.7874 -0.4064)
			(end 0.7874 0.4064)
			(stroke
				(width 0.1524)
				(type default)
			)
			(layer "F.SilkS")
		)
		(fp_line
			(start 0.7874 0.4064)
			(end -0.7874 0.4064)
			(stroke
				(width 0.1524)
				(type default)
			)
			(layer "F.SilkS")
		)
		(fp_line
			(start -0.67945 -0.305054)
			(end -0.12065 -0.305054)
			(stroke
				(width 0.1)
				(type default)
			)
			(layer "F.Fab")
		)
		(fp_line
			(start -0.67945 0.3048)
			(end -0.67945 -0.305054)
			(stroke
				(width 0.1)
				(type default)
			)
			(layer "F.Fab")
		)
		(fp_line
			(start -0.12065 -0.305054)
			(end -0.12065 -0.2794)
			(stroke
				(width 0.1)
				(type default)
			)
			(layer "F.Fab")
		)
		(fp_line
			(start -0.12065 -0.2794)
			(end 0.12065 -0.2794)
			(stroke
				(width 0.1)
				(type default)
			)
			(layer "F.Fab")
		)
		(fp_line
			(start -0.12065 0.2794)
			(end -0.12065 0.3048)
			(stroke
				(width 0.1)
				(type default)
			)
			(layer "F.Fab")
		)
		(fp_line
			(start -0.12065 0.3048)
			(end -0.67945 0.3048)
			(stroke
				(width 0.1)
				(type default)
			)
			(layer "F.Fab")
		)
		(fp_line
			(start 0.120396 0.2794)
			(end -0.12065 0.2794)
			(stroke
				(width 0.1)
				(type default)
			)
			(layer "F.Fab")
		)
		(fp_line
			(start 0.120396 0.3048)
			(end 0.120396 0.2794)
			(stroke
				(width 0.1)
				(type default)
			)
			(layer "F.Fab")
		)
		(fp_line
			(start 0.12065 -0.3048)
			(end 0.67945 -0.3048)
			(stroke
				(width 0.1)
				(type default)
			)
			(layer "F.Fab")
		)
		(fp_line
			(start 0.12065 -0.2794)
			(end 0.12065 -0.3048)
			(stroke
				(width 0.1)
				(type default)
			)
			(layer "F.Fab")
		)
		(fp_line
			(start 0.67945 -0.3048)
			(end 0.67945 0.3048)
			(stroke
				(width 0.1)
				(type default)
			)
			(layer "F.Fab")
		)
		(fp_line
			(start 0.67945 0.3048)
			(end 0.120396 0.3048)
			(stroke
				(width 0.1)
				(type default)
			)
			(layer "F.Fab")
		)
		(pad "1" smd circle
			(at -0.40005 0)
			(size 0 0)
			(layers "F.Cu" "F.Mask" "F.Paste")
			(net "SVID_CLK0_CPU0_R")
		)
		(pad "2" smd circle
			(at 0.40005 0)
			(size 0 0)
			(layers "F.Cu" "F.Mask" "F.Paste")
			(net "SVID_CLK_PVCCIN_CPU0_R")
		)
	)
	(footprint ""
		(layer "F.Cu")
		(at 134.92988 -74.259948 90)
		(property "Reference" "C563"
			(at 0 0 90)
			(layer "F.SilkS")
			(hide yes)
			(effects
				(font
					(size 1.27 1.27)
				)
			)
		)
		(property "Value" ""
			(at 0 0 90)
			(layer "F.Fab")
			(effects
				(font
					(size 1.27 1.27)
				)
			)
		)
		(duplicate_pad_numbers_are_jumpers no)
		(fp_line
			(start 1.524 -0.762)
			(end 1.524 0.762)
			(stroke
				(width 0.1524)
				(type default)
			)
			(layer "F.SilkS")
		)
		(fp_line
			(start -1.524 -0.762)
			(end 1.524 -0.762)
			(stroke
				(width 0.1524)
				(type default)
			)
			(layer "F.SilkS")
		)
		(fp_line
			(start 1.524 0.762)
			(end -1.524 0.762)
			(stroke
				(width 0.1524)
				(type default)
			)
			(layer "F.SilkS")
		)
		(fp_line
			(start -1.524 0.762)
			(end -1.524 -0.762)
			(stroke
				(width 0.1524)
				(type default)
			)
			(layer "F.SilkS")
		)
		(fp_line
			(start 1.1049 -0.724916)
			(end -1.1049 -0.724916)
			(stroke
				(width 0.1)
				(type default)
			)
			(layer "F.Fab")
		)
		(fp_line
			(start -1.1049 -0.724916)
			(end -1.1049 0.724916)
			(stroke
				(width 0.1)
				(type default)
			)
			(layer "F.Fab")
		)
		(fp_line
			(start 1.1049 0.724916)
			(end 1.1049 -0.724916)
			(stroke
				(width 0.1)
				(type default)
			)
			(layer "F.Fab")
		)
		(fp_line
			(start -1.1049 0.724916)
			(end 1.1049 0.724916)
			(stroke
				(width 0.1)
				(type default)
			)
			(layer "F.Fab")
		)
		(pad "1" smd rect
			(at -0.889 0 270)
			(size 1.016 1.27)
			(layers "F.Cu" "F.Mask" "F.Paste")
			(net "P3V3_AUX_BMC_D")
		)
		(pad "2" smd rect
			(at 0.889 0 270)
			(size 1.016 1.27)
			(layers "F.Cu" "F.Mask" "F.Paste")
			(net "GND")
		)
	)
	(footprint ""
		(layer "F.Cu")
		(at 438.256172 -32.173418 90)
		(property "Reference" "PR3837"
			(at 0 0 90)
			(layer "F.SilkS")
			(hide yes)
			(effects
				(font
					(size 1.27 1.27)
				)
			)
		)
		(property "Value" ""
			(at 0 0 90)
			(layer "F.Fab")
			(effects
				(font
					(size 1.27 1.27)
				)
			)
		)
		(duplicate_pad_numbers_are_jumpers no)
		(fp_line
			(start 0.7874 -0.4064)
			(end 0.7874 0.4064)
			(stroke
				(width 0.1524)
				(type default)
			)
			(layer "F.SilkS")
		)
		(fp_line
			(start -0.7874 -0.4064)
			(end 0.7874 -0.4064)
			(stroke
				(width 0.1524)
				(type default)
			)
			(layer "F.SilkS")
		)
		(fp_line
			(start 0.7874 0.4064)
			(end -0.7874 0.4064)
			(stroke
				(width 0.1524)
				(type default)
			)
			(layer "F.SilkS")
		)
		(fp_line
			(start -0.7874 0.4064)
			(end -0.7874 -0.4064)
			(stroke
				(width 0.1524)
				(type default)
			)
			(layer "F.SilkS")
		)
		(fp_line
			(start -0.12065 -0.305054)
			(end -0.12065 -0.2794)
			(stroke
				(width 0.1)
				(type default)
			)
			(layer "F.Fab")
		)
		(fp_line
			(start -0.67945 -0.305054)
			(end -0.12065 -0.305054)
			(stroke
				(width 0.1)
				(type default)
			)
			(layer "F.Fab")
		)
		(fp_line
			(start 0.67945 -0.3048)
			(end 0.67945 0.3048)
			(stroke
				(width 0.1)
				(type default)
			)
			(layer "F.Fab")
		)
		(fp_line
			(start 0.12065 -0.3048)
			(end 0.67945 -0.3048)
			(stroke
				(width 0.1)
				(type default)
			)
			(layer "F.Fab")
		)
		(fp_line
			(start 0.12065 -0.2794)
			(end 0.12065 -0.3048)
			(stroke
				(width 0.1)
				(type default)
			)
			(layer "F.Fab")
		)
		(fp_line
			(start -0.12065 -0.2794)
			(end 0.12065 -0.2794)
			(stroke
				(width 0.1)
				(type default)
			)
			(layer "F.Fab")
		)
		(fp_line
			(start 0.120396 0.2794)
			(end -0.12065 0.2794)
			(stroke
				(width 0.1)
				(type default)
			)
			(layer "F.Fab")
		)
		(fp_line
			(start -0.12065 0.2794)
			(end -0.12065 0.3048)
			(stroke
				(width 0.1)
				(type default)
			)
			(layer "F.Fab")
		)
		(fp_line
			(start 0.67945 0.3048)
			(end 0.120396 0.3048)
			(stroke
				(width 0.1)
				(type default)
			)
			(layer "F.Fab")
		)
		(fp_line
			(start 0.120396 0.3048)
			(end 0.120396 0.2794)
			(stroke
				(width 0.1)
				(type default)
			)
			(layer "F.Fab")
		)
		(fp_line
			(start -0.12065 0.3048)
			(end -0.67945 0.3048)
			(stroke
				(width 0.1)
				(type default)
			)
			(layer "F.Fab")
		)
		(fp_line
			(start -0.67945 0.3048)
			(end -0.67945 -0.305054)
			(stroke
				(width 0.1)
				(type default)
			)
			(layer "F.Fab")
		)
		(pad "1" smd circle
			(at -0.40005 0 90)
			(size 0 0)
			(layers "F.Cu" "F.Mask" "F.Paste")
			(net "P12V_OCP_IMON_1")
		)
		(pad "2" smd circle
			(at 0.40005 0 90)
			(size 0 0)
			(layers "F.Cu" "F.Mask" "F.Paste")
			(net "GND")
		)
	)
	(footprint ""
		(layer "F.Cu")
		(at 36.956238 -129.74574 180)
		(property "Reference" "R2559"
			(at 0 0 180)
			(layer "F.SilkS")
			(hide yes)
			(effects
				(font
					(size 1.27 1.27)
				)
			)
		)
		(property "Value" ""
			(at 0 0 180)
			(layer "F.Fab")
			(effects
				(font
					(size 1.27 1.27)
				)
			)
		)
		(duplicate_pad_numbers_are_jumpers no)
		(fp_line
			(start 0.7874 0.4064)
			(end -0.7874 0.4064)
			(stroke
				(width 0.1524)
				(type default)
			)
			(layer "F.SilkS")
		)
		(fp_line
			(start 0.7874 -0.4064)
			(end 0.7874 0.4064)
			(stroke
				(width 0.1524)
				(type default)
			)
			(layer "F.SilkS")
		)
		(fp_line
			(start -0.7874 0.4064)
			(end -0.7874 -0.4064)
			(stroke
				(width 0.1524)
				(type default)
			)
			(layer "F.SilkS")
		)
		(fp_line
			(start -0.7874 -0.4064)
			(end 0.7874 -0.4064)
			(stroke
				(width 0.1524)
				(type default)
			)
			(layer "F.SilkS")
		)
		(fp_line
			(start 0.67945 0.3048)
			(end 0.120396 0.3048)
			(stroke
				(width 0.1)
				(type default)
			)
			(layer "F.Fab")
		)
		(fp_line
			(start 0.67945 -0.3048)
			(end 0.67945 0.3048)
			(stroke
				(width 0.1)
				(type default)
			)
			(layer "F.Fab")
		)
		(fp_line
			(start 0.12065 -0.2794)
			(end 0.12065 -0.3048)
			(stroke
				(width 0.1)
				(type default)
			)
			(layer "F.Fab")
		)
		(fp_line
			(start 0.12065 -0.3048)
			(end 0.67945 -0.3048)
			(stroke
				(width 0.1)
				(type default)
			)
			(layer "F.Fab")
		)
		(fp_line
			(start 0.120396 0.3048)
			(end 0.120396 0.2794)
			(stroke
				(width 0.1)
				(type default)
			)
			(layer "F.Fab")
		)
		(fp_line
			(start 0.120396 0.2794)
			(end -0.12065 0.2794)
			(stroke
				(width 0.1)
				(type default)
			)
			(layer "F.Fab")
		)
		(fp_line
			(start -0.12065 0.3048)
			(end -0.67945 0.3048)
			(stroke
				(width 0.1)
				(type default)
			)
			(layer "F.Fab")
		)
		(fp_line
			(start -0.12065 0.2794)
			(end -0.12065 0.3048)
			(stroke
				(width 0.1)
				(type default)
			)
			(layer "F.Fab")
		)
		(fp_line
			(start -0.12065 -0.2794)
			(end 0.12065 -0.2794)
			(stroke
				(width 0.1)
				(type default)
			)
			(layer "F.Fab")
		)
		(fp_line
			(start -0.12065 -0.305054)
			(end -0.12065 -0.2794)
			(stroke
				(width 0.1)
				(type default)
			)
			(layer "F.Fab")
		)
		(fp_line
			(start -0.67945 0.3048)
			(end -0.67945 -0.305054)
			(stroke
				(width 0.1)
				(type default)
			)
			(layer "F.Fab")
		)
		(fp_line
			(start -0.67945 -0.305054)
			(end -0.12065 -0.305054)
			(stroke
				(width 0.1)
				(type default)
			)
			(layer "F.Fab")
		)
		(pad "1" smd circle
			(at -0.40005 0 180)
			(size 0 0)
			(layers "F.Cu" "F.Mask" "F.Paste")
			(net "SVID_CLK0_CPU1_R")
		)
		(pad "2" smd circle
			(at 0.40005 0 180)
			(size 0 0)
			(layers "F.Cu" "F.Mask" "F.Paste")
			(net "SVID_CLK_PVCCINFAON_CPU1_R")
		)
	)
	(footprint ""
		(layer "F.Cu")
		(at 430.600104 -139.574778)
		(property "Reference" "C3275"
			(at 0 0 0)
			(layer "F.SilkS")
			(hide yes)
			(effects
				(font
					(size 1.27 1.27)
				)
			)
		)
		(property "Value" ""
			(at 0 0 0)
			(layer "F.Fab")
			(effects
				(font
					(size 1.27 1.27)
				)
			)
		)
		(duplicate_pad_numbers_are_jumpers no)
		(fp_line
			(start -0.7874 -0.4064)
			(end 0.7874 -0.4064)
			(stroke
				(width 0.1524)
				(type default)
			)
			(layer "F.SilkS")
		)
		(fp_line
			(start -0.7874 0.4064)
			(end -0.7874 -0.4064)
			(stroke
				(width 0.1524)
				(type default)
			)
			(layer "F.SilkS")
		)
		(fp_line
			(start 0.7874 -0.4064)
			(end 0.7874 0.4064)
			(stroke
				(width 0.1524)
				(type default)
			)
			(layer "F.SilkS")
		)
		(fp_line
			(start 0.7874 0.4064)
			(end -0.7874 0.4064)
			(stroke
				(width 0.1524)
				(type default)
			)
			(layer "F.SilkS")
		)
		(fp_line
			(start -0.67945 -0.305054)
			(end -0.12065 -0.305054)
			(stroke
				(width 0.1)
				(type default)
			)
			(layer "F.Fab")
		)
		(fp_line
			(start -0.67945 0.3048)
			(end -0.67945 -0.305054)
			(stroke
				(width 0.1)
				(type default)
			)
			(layer "F.Fab")
		)
		(fp_line
			(start -0.12065 -0.305054)
			(end -0.12065 -0.2794)
			(stroke
				(width 0.1)
				(type default)
			)
			(layer "F.Fab")
		)
		(fp_line
			(start -0.12065 -0.2794)
			(end 0.12065 -0.2794)
			(stroke
				(width 0.1)
				(type default)
			)
			(layer "F.Fab")
		)
		(fp_line
			(start -0.12065 0.2794)
			(end -0.12065 0.3048)
			(stroke
				(width 0.1)
				(type default)
			)
			(layer "F.Fab")
		)
		(fp_line
			(start -0.12065 0.3048)
			(end -0.67945 0.3048)
			(stroke
				(width 0.1)
				(type default)
			)
			(layer "F.Fab")
		)
		(fp_line
			(start 0.120396 0.2794)
			(end -0.12065 0.2794)
			(stroke
				(width 0.1)
				(type default)
			)
			(layer "F.Fab")
		)
		(fp_line
			(start 0.120396 0.3048)
			(end 0.120396 0.2794)
			(stroke
				(width 0.1)
				(type default)
			)
			(layer "F.Fab")
		)
		(fp_line
			(start 0.12065 -0.3048)
			(end 0.67945 -0.3048)
			(stroke
				(width 0.1)
				(type default)
			)
			(layer "F.Fab")
		)
		(fp_line
			(start 0.12065 -0.2794)
			(end 0.12065 -0.3048)
			(stroke
				(width 0.1)
				(type default)
			)
			(layer "F.Fab")
		)
		(fp_line
			(start 0.67945 -0.3048)
			(end 0.67945 0.3048)
			(stroke
				(width 0.1)
				(type default)
			)
			(layer "F.Fab")
		)
		(fp_line
			(start 0.67945 0.3048)
			(end 0.120396 0.3048)
			(stroke
				(width 0.1)
				(type default)
			)
			(layer "F.Fab")
		)
		(pad "1" smd circle
			(at -0.40005 0)
			(size 0 0)
			(layers "F.Cu" "F.Mask" "F.Paste")
			(net "PVCCFA_EHV_CPU0_EN_R")
		)
		(pad "2" smd circle
			(at 0.40005 0)
			(size 0 0)
			(layers "F.Cu" "F.Mask" "F.Paste")
			(net "GND")
		)
	)
)
